(kicad_pcb
	(version 20221018)
	(generator pcbnew)
	(general
    (thickness 1.7403)
  )
	(paper "A4")
	(title_block
    (title "Data Center RDIMM DDR4 Tester")
    (date "2024-09-30")
    (rev "1.2.4")
		(comment 9 "footprints 321-329 of 690")
	)
	(layers
    (0 "F.Cu" signal)
    (1 "In1.Cu" power)
    (2 "In2.Cu" signal)
    (3 "In3.Cu" power)
    (4 "In4.Cu" power)
    (5 "In5.Cu" signal)
    (6 "In6.Cu" power)
    (7 "In7.Cu" signal)
    (8 "In8.Cu" power)
    (9 "In9.Cu" signal)
    (10 "In10.Cu" power)
    (31 "B.Cu" signal)
    (32 "B.Adhes" user "B.Adhesive")
    (33 "F.Adhes" user "F.Adhesive")
    (34 "B.Paste" user)
    (35 "F.Paste" user)
    (36 "B.SilkS" user "B.Silkscreen")
    (37 "F.SilkS" user "F.Silkscreen")
    (38 "B.Mask" user)
    (39 "F.Mask" user)
    (40 "Dwgs.User" user "User.Drawings")
    (41 "Cmts.User" user "User.Comments")
    (42 "Eco1.User" user "User.Eco1")
    (43 "Eco2.User" user "User.Eco2")
    (44 "Edge.Cuts" user)
    (45 "Margin" user)
    (46 "B.CrtYd" user "B.Courtyard")
    (47 "F.CrtYd" user "F.Courtyard")
    (48 "B.Fab" user)
    (49 "F.Fab" user)
  )
	(footprint "data-center-rdimm-ddr4-tester-footprints:C_0402_1005Metric" (layer "F.Cu")
    (at 243.71 122.975)
    (descr "Capacitor SMD 0402")
    (tags "capacitor SMD 0402")
    (property "Author" "Antmicro")
    (property "Dielectric" "X5R")
    (property "License" "Apache-2.0")
    (property "MPN" "GRM155R61H104KE14D")
    (property "Manufacturer" "Murata")
    (property "Sheetfile" "pcie.kicad_sch")
    (property "Sheetname" "FPGA banks 115-116")
    (property "Val" "100n")
    (property "Voltage" "50V")
    (property "ki_description" " ")
    (attr smd)
    (fp_text reference "C317" (at -2.82 -1.475) (layer "F.SilkS")
        (effects (font (size 0.7 0.7) (thickness 0.15)) (justify left bottom))
    )
    (fp_text value "C_100n_0402" (at 0 1.4) (layer "F.Fab") hide
        (effects (font (size 0.7 0.7) (thickness 0.15)) (justify left bottom))
    )
    (fp_text user "License: Apache-2.0" (at -0.932 5.17) (layer "F.Fab") hide
        (effects (font (size 0.7 0.7) (thickness 0.15)) (justify left bottom))
    )
    (fp_text user "${REFERENCE}" (at -0.932 3.168) (layer "F.Fab") hide
        (effects (font (size 0.7 0.7) (thickness 0.15)) (justify left bottom))
    )
    (fp_text user "Author: Antmicro" (at -0.932 4.17) (layer "F.Fab") hide
        (effects (font (size 0.7 0.7) (thickness 0.15)) (justify left bottom))
    )
    (fp_rect (start -0.94 -0.47) (end 0.94 0.47)
      (stroke (width 0.05) (type solid)) (fill none) (layer "F.CrtYd"))
    (fp_rect (start -0.499 -0.249) (end 0.499 0.249)
      (stroke (width 0.15) (type solid)) (fill none) (layer "F.Fab"))
    (pad "1" smd roundrect (at -0.484 0) (size 0.59 0.64) (layers "F.Cu" "F.Paste" "F.Mask") (roundrect_rratio 0.25)
      (net 887 "/FPGA banks 115-116/GTR_REFCLK3_P") (pintype "passive"))
    (pad "2" smd roundrect (at 0.484 0) (size 0.59 0.64) (layers "F.Cu" "F.Paste" "F.Mask") (roundrect_rratio 0.25)
      (net 895 "GTR_REFCLK3_C_P") (pintype "passive"))
  )
	(footprint "data-center-rdimm-ddr4-tester-footprints:R_1206_3216Metric" (layer "F.Cu")
    (at 131.6 99.5 90)
    (property "Author" "Antmicro")
    (property "License" "Apache-2.0")
    (property "MPN" "RL1206FR-7W0R01L")
    (property "Manufacturer" "Yaego")
    (property "Sheetfile" "supply.kicad_sch")
    (property "Sheetname" "Supply")
    (property "Tolerance" "1%")
    (property "Val" "0R01")
    (property "ki_description" "0R01 resistor in 1206 package with unspecified tolerance")
    (attr smd)
    (fp_text reference "R201" (at -2.03 -1.1 90) (layer "F.SilkS")
        (effects (font (size 0.7 0.7) (thickness 0.15)) (justify left bottom))
    )
    (fp_text value "R_0R01_1206" (at 0 2 90) (layer "F.Fab") hide
        (effects (font (size 0.7 0.7) (thickness 0.15)) (justify left bottom))
    )
    (fp_text user "License: Apache-2.0" (at -2.401 6.3 90) (layer "F.Fab") hide
        (effects (font (size 0.7 0.7) (thickness 0.15)) (justify left bottom))
    )
    (fp_text user "${REFERENCE}" (at -2.401 3.5 90) (layer "F.Fab") hide
        (effects (font (size 0.7 0.7) (thickness 0.15)) (justify left bottom))
    )
    (fp_text user "Author: Antmicro" (at -2.401 4.899 90) (layer "F.Fab") hide
        (effects (font (size 0.7 0.7) (thickness 0.15)) (justify left bottom))
    )
    (fp_line (start 0 -0.902) (end -0.5 -0.902)
      (stroke (width 0.15) (type solid)) (layer "F.SilkS"))
    (fp_line (start 0 -0.902) (end 0.498 -0.902)
      (stroke (width 0.15) (type solid)) (layer "F.SilkS"))
    (fp_line (start 0 0.9) (end -0.5 0.9)
      (stroke (width 0.15) (type solid)) (layer "F.SilkS"))
    (fp_line (start 0 0.9) (end 0.498 0.9)
      (stroke (width 0.15) (type solid)) (layer "F.SilkS"))
    (fp_rect (start -2.25 -1.05) (end 2.25 1.05)
      (stroke (width 0.05) (type solid)) (fill none) (layer "F.CrtYd"))
    (fp_line (start -1.601 -0.802) (end -1.601 0.8)
      (stroke (width 0.15) (type solid)) (layer "F.Fab"))
    (fp_line (start -1.601 -0.802) (end 1.6 -0.802)
      (stroke (width 0.15) (type solid)) (layer "F.Fab"))
    (fp_line (start -1.601 0.8) (end 1.6 0.8)
      (stroke (width 0.15) (type solid)) (layer "F.Fab"))
    (fp_line (start 1.6 -0.802) (end 1.6 0.8)
      (stroke (width 0.15) (type solid)) (layer "F.Fab"))
    (pad "1" smd roundrect (at -1.5 0 90) (size 1.2 1.8) (layers "F.Cu" "F.Paste" "F.Mask") (roundrect_rratio 0.15)
      (net 104 "VCC5V0") (pintype "passive"))
    (pad "2" smd roundrect (at 1.499 0 90) (size 1.2 1.8) (layers "F.Cu" "F.Paste" "F.Mask") (roundrect_rratio 0.15)
      (net 307 "5V0_SYS") (pintype "passive"))
  )
	(footprint "data-center-rdimm-ddr4-tester-footprints:NetTie-2_SMD_Pad0.127mm" (layer "F.Cu")
    (at 143.03 83.7 180)
    (descr "Net tie, 2 pin, 0.127mm  SMD pads")
    (tags "net tie")
    (property "Author" "Antmicro")
    (property "License" "Apache-2.0")
    (property "MPN" "")
    (property "Manufacturer" "")
    (property "Sheetfile" "supply.kicad_sch")
    (property "Sheetname" "Supply")
    (property "ki_description" "Net tie, 2 pins")
    (property "ki_keywords" "net tie short")
    (attr through_hole exclude_from_pos_files)
    (net_tie_pad_groups "1, 2")
    (fp_text reference "NT10" (at -0.128 -1.345 180) (layer "F.SilkS") hide
        (effects (font (size 0.7 0.7) (thickness 0.15)) (justify left bottom))
    )
    (fp_text value "Net-Tie_2" (at 0 1.199 180) (layer "F.Fab") hide
        (effects (font (size 0.7 0.7) (thickness 0.15)) (justify left bottom))
    )
    (fp_text user "License: Apache-2.0" (at -0.128 5.6 180) (layer "F.Fab") hide
        (effects (font (size 0.7 0.7) (thickness 0.15)) (justify left bottom))
    )
    (fp_text user "Author: Antmicro" (at -0.128 4.4 180) (layer "F.Fab") hide
        (effects (font (size 0.7 0.7) (thickness 0.15)) (justify left bottom))
    )
    (fp_text user "${REFERENCE}" (at -0.128 3.2 180) (layer "F.Fab") hide
        (effects (font (size 0.7 0.7) (thickness 0.15)) (justify left bottom))
    )
    (fp_poly
      (pts
        (xy -0.0635 -0.0635)
        (xy 0.0625 -0.0635)
        (xy 0.0625 0.0635)
        (xy -0.0635 0.0635)
      )

      (stroke (width 0) (type solid)) (fill solid) (layer "F.Cu"))
    (pad "1" smd roundrect (at -0.127 0) (size 0.127 0.127) (layers "F.Cu") (roundrect_rratio 0.5)
      (chamfer_ratio 0) (chamfer top_left bottom_left)
      (net 841 "/Supply/1V0_SEN_+") (pinfunction "1") (pintype "passive"))
    (pad "2" smd roundrect (at 0.126 0 180) (size 0.127 0.127) (layers "F.Cu") (roundrect_rratio 0.5)
      (chamfer_ratio 0) (chamfer top_left bottom_left)
      (net 300 "VCC1V0") (pinfunction "2") (pintype "passive"))
  )
	(footprint "data-center-rdimm-ddr4-tester-footprints:R_0402_1005Metric" (layer "F.Cu")
    (at 109.875 112.075 180)
    (descr "Resistor SMD 0402")
    (tags "resistor SMD 0402")
    (property "Author" "Antmicro")
    (property "Current" "1A")
    (property "DNP" "DNP")
    (property "License" "Apache-2.0")
    (property "MPN" "ERJ2GE0R00X")
    (property "Manufacturer" "Panasonic")
    (property "Sheetfile" "DDR4.kicad_sch")
    (property "Sheetname" "DDR4")
    (property "Tolerance" "")
    (property "Val" "0R")
    (property "dnp" "")
    (property "exclude_from_bom" "")
    (property "ki_description" "0R resistor in 0402 package with unspecified tolerance")
    (attr exclude_from_pos_files exclude_from_bom)
    (fp_text reference "R157" (at 2.785 0.475 180) (layer "F.SilkS")
        (effects (font (size 0.7 0.7) (thickness 0.15)) (justify left bottom))
    )
    (fp_text value "R_0R_0402" (at 0 1.4 180) (layer "F.Fab") hide
        (effects (font (size 0.7 0.7) (thickness 0.15)) (justify left bottom))
    )
    (fp_text user "Author: Antmicro" (at -0.95 4.169 180) (layer "F.Fab") hide
        (effects (font (size 0.7 0.7) (thickness 0.15)) (justify left bottom))
    )
    (fp_text user "License: Apache-2.0" (at -0.95 5.169 180) (layer "F.Fab") hide
        (effects (font (size 0.7 0.7) (thickness 0.15)) (justify left bottom))
    )
    (fp_text user "${REFERENCE}" (at -0.95 3.168 180) (layer "F.Fab") hide
        (effects (font (size 0.7 0.7) (thickness 0.15)) (justify left bottom))
    )
    (fp_rect (start -0.93 -0.47) (end 0.93 0.47)
      (stroke (width 0.05) (type solid)) (fill none) (layer "F.CrtYd"))
    (fp_rect (start -0.5 -0.25) (end 0.5 0.25)
      (stroke (width 0.15) (type solid)) (fill none) (layer "F.Fab"))
    (pad "1" smd roundrect (at -0.485 0 180) (size 0.59 0.64) (layers "F.Cu" "F.Paste" "F.Mask") (roundrect_rratio 0.25)
      (net 103 "VIN") (pintype "passive"))
    (pad "2" smd roundrect (at 0.485 0 180) (size 0.59 0.64) (layers "F.Cu" "F.Paste" "F.Mask") (roundrect_rratio 0.25)
      (net 308 "NC") (pintype "passive"))
  )
	(footprint "data-center-rdimm-ddr4-tester-footprints:C_0402_1005Metric" (layer "F.Cu")
    (at 162.7 104.51 -90)
    (descr "Capacitor SMD 0402")
    (tags "capacitor SMD 0402")
    (property "Author" "Antmicro")
    (property "DNP" "DNP")
    (property "Dielectric" "X5R")
    (property "License" "Apache-2.0")
    (property "MPN" "GRM155R61H104KE14D")
    (property "Manufacturer" "Murata")
    (property "Sheetfile" "ethernet.kicad_sch")
    (property "Sheetname" "Ethernet")
    (property "Val" "100n")
    (property "Voltage" "50V")
    (property "dnp" "")
    (property "exclude_from_bom" "")
    (property "ki_description" " ")
    (attr exclude_from_pos_files exclude_from_bom)
    (fp_text reference "C291" (at 3.58 -0.34 -90) (layer "F.SilkS")
        (effects (font (size 0.7 0.7) (thickness 0.15)) (justify left bottom))
    )
    (fp_text value "C_100n_0402" (at 0 1.4 -90) (layer "F.Fab") hide
        (effects (font (size 0.7 0.7) (thickness 0.15)) (justify left bottom))
    )
    (fp_text user "Author: Antmicro" (at -0.932 4.17 -90) (layer "F.Fab") hide
        (effects (font (size 0.7 0.7) (thickness 0.15)) (justify left bottom))
    )
    (fp_text user "${REFERENCE}" (at -0.932 3.168 -90) (layer "F.Fab") hide
        (effects (font (size 0.7 0.7) (thickness 0.15)) (justify left bottom))
    )
    (fp_text user "License: Apache-2.0" (at -0.932 5.17 -90) (layer "F.Fab") hide
        (effects (font (size 0.7 0.7) (thickness 0.15)) (justify left bottom))
    )
    (fp_rect (start -0.94 -0.47) (end 0.94 0.47)
      (stroke (width 0.05) (type solid)) (fill none) (layer "F.CrtYd"))
    (fp_rect (start -0.499 -0.249) (end 0.499 0.249)
      (stroke (width 0.15) (type solid)) (fill none) (layer "F.Fab"))
    (pad "1" smd roundrect (at -0.484 0 270) (size 0.59 0.64) (layers "F.Cu" "F.Paste" "F.Mask") (roundrect_rratio 0.25)
      (net 143 "3V3_SYS") (pintype "passive"))
    (pad "2" smd roundrect (at 0.484 0 270) (size 0.59 0.64) (layers "F.Cu" "F.Paste" "F.Mask") (roundrect_rratio 0.25)
      (net 9 "GND") (pintype "passive"))
  )
	(footprint "data-center-rdimm-ddr4-tester-footprints:C_0402_1005Metric" (layer "F.Cu")
    (at 153.2 127.515 90)
    (descr "Capacitor SMD 0402")
    (tags "capacitor SMD 0402")
    (property "Author" "Antmicro")
    (property "Dielectric" "X5R")
    (property "License" "Apache-2.0")
    (property "MPN" "GRM155R61H104KE14D")
    (property "Manufacturer" "Murata")
    (property "Sheetfile" "interfaces.kicad_sch")
    (property "Sheetname" "Interfaces")
    (property "Val" "100n")
    (property "Voltage" "50V")
    (property "ki_description" " ")
    (attr smd)
    (fp_text reference "C252" (at -0.965 -0.41 90) (layer "F.SilkS")
        (effects (font (size 0.7 0.7) (thickness 0.15)) (justify left bottom))
    )
    (fp_text value "C_100n_0402" (at 0 1.4 90) (layer "F.Fab") hide
        (effects (font (size 0.7 0.7) (thickness 0.15)) (justify left bottom))
    )
    (fp_text user "Author: Antmicro" (at -0.932 4.17 90) (layer "F.Fab") hide
        (effects (font (size 0.7 0.7) (thickness 0.15)) (justify left bottom))
    )
    (fp_text user "${REFERENCE}" (at -0.932 3.168 90) (layer "F.Fab") hide
        (effects (font (size 0.7 0.7) (thickness 0.15)) (justify left bottom))
    )
    (fp_text user "License: Apache-2.0" (at -0.932 5.17 90) (layer "F.Fab") hide
        (effects (font (size 0.7 0.7) (thickness 0.15)) (justify left bottom))
    )
    (fp_rect (start -0.94 -0.47) (end 0.94 0.47)
      (stroke (width 0.05) (type solid)) (fill none) (layer "F.CrtYd"))
    (fp_rect (start -0.499 -0.249) (end 0.499 0.249)
      (stroke (width 0.15) (type solid)) (fill none) (layer "F.Fab"))
    (pad "1" smd roundrect (at -0.484 0 90) (size 0.59 0.64) (layers "F.Cu" "F.Paste" "F.Mask") (roundrect_rratio 0.25)
      (net 862 "GNDS") (pintype "passive"))
    (pad "2" smd roundrect (at 0.484 0 90) (size 0.59 0.64) (layers "F.Cu" "F.Paste" "F.Mask") (roundrect_rratio 0.25)
      (net 9 "GND") (pintype "passive"))
  )
	(footprint "data-center-rdimm-ddr4-tester-footprints:R_0402_1005Metric" (layer "F.Cu")
    (at 246.042902 122.36 180)
    (descr "Resistor SMD 0402")
    (tags "resistor SMD 0402")
    (property "Author" "Antmicro")
    (property "License" "Apache-2.0")
    (property "MPN" "CR0402-FX-33R0GLF")
    (property "Manufacturer" "Bourns")
    (property "Sheetfile" "fmc_hpc.kicad_sch")
    (property "Sheetname" "FMC HPC")
    (property "Tolerance" "1%")
    (property "Val" "33R")
    (property "ki_description" "33R resistor in 0402 package with 1% tolerance")
    (attr smd)
    (fp_text reference "R153" (at -0.697098 -0.37 180) (layer "F.SilkS")
        (effects (font (size 0.7 0.7) (thickness 0.15)) (justify left bottom))
    )
    (fp_text value "R_33R_0402" (at 0 1.4 180) (layer "F.Fab") hide
        (effects (font (size 0.7 0.7) (thickness 0.15)) (justify left bottom))
    )
    (fp_text user "License: Apache-2.0" (at -0.95 5.169 180) (layer "F.Fab") hide
        (effects (font (size 0.7 0.7) (thickness 0.15)) (justify left bottom))
    )
    (fp_text user "${REFERENCE}" (at -0.95 3.168 180) (layer "F.Fab") hide
        (effects (font (size 0.7 0.7) (thickness 0.15)) (justify left bottom))
    )
    (fp_text user "Author: Antmicro" (at -0.95 4.169 180) (layer "F.Fab") hide
        (effects (font (size 0.7 0.7) (thickness 0.15)) (justify left bottom))
    )
    (fp_rect (start -0.93 -0.47) (end 0.93 0.47)
      (stroke (width 0.05) (type solid)) (fill none) (layer "F.CrtYd"))
    (fp_rect (start -0.5 -0.25) (end 0.5 0.25)
      (stroke (width 0.15) (type solid)) (fill none) (layer "F.Fab"))
    (pad "1" smd roundrect (at -0.485 0 180) (size 0.59 0.64) (layers "F.Cu" "F.Paste" "F.Mask") (roundrect_rratio 0.25)
      (net 900 "/FMC HPC/GTR_REFCLK3_R_N") (pintype "passive"))
    (pad "2" smd roundrect (at 0.485 0 180) (size 0.59 0.64) (layers "F.Cu" "F.Paste" "F.Mask") (roundrect_rratio 0.25)
      (net 896 "GTR_REFCLK3_C_N") (pintype "passive"))
  )
	(footprint "data-center-rdimm-ddr4-tester-footprints:R_0402_1005Metric" (layer "F.Cu")
    (at 250.9 114.5 180)
    (descr "Resistor SMD 0402")
    (tags "resistor SMD 0402")
    (property "Author" "Antmicro")
    (property "License" "Apache-2.0")
    (property "MPN" "CR0402-FX-1002GLF")
    (property "Manufacturer" "Bourns")
    (property "Sheetfile" "fmc_hpc.kicad_sch")
    (property "Sheetname" "FMC HPC")
    (property "Tolerance" "1%")
    (property "Val" "10k")
    (property "ki_description" "10k resistor in 0402 package with 1% tolerance")
    (attr smd)
    (fp_text reference "R209" (at 3.7 -0.4 180) (layer "F.SilkS")
        (effects (font (size 0.7 0.7) (thickness 0.15)) (justify left bottom))
    )
    (fp_text value "R_10k_0402" (at 0 1.4 180) (layer "F.Fab") hide
        (effects (font (size 0.7 0.7) (thickness 0.15)) (justify left bottom))
    )
    (fp_text user "License: Apache-2.0" (at -0.95 5.169 180) (layer "F.Fab") hide
        (effects (font (size 0.7 0.7) (thickness 0.15)) (justify left bottom))
    )
    (fp_text user "${REFERENCE}" (at -0.95 3.168 180) (layer "F.Fab") hide
        (effects (font (size 0.7 0.7) (thickness 0.15)) (justify left bottom))
    )
    (fp_text user "Author: Antmicro" (at -0.95 4.169 180) (layer "F.Fab") hide
        (effects (font (size 0.7 0.7) (thickness 0.15)) (justify left bottom))
    )
    (fp_rect (start -0.93 -0.47) (end 0.93 0.47)
      (stroke (width 0.05) (type solid)) (fill none) (layer "F.CrtYd"))
    (fp_rect (start -0.5 -0.25) (end 0.5 0.25)
      (stroke (width 0.15) (type solid)) (fill none) (layer "F.Fab"))
    (pad "1" smd roundrect (at -0.485 0 180) (size 0.59 0.64) (layers "F.Cu" "F.Paste" "F.Mask") (roundrect_rratio 0.25)
      (net 120 "~{PERST}") (pintype "passive"))
    (pad "2" smd roundrect (at 0.485 0 180) (size 0.59 0.64) (layers "F.Cu" "F.Paste" "F.Mask") (roundrect_rratio 0.25)
      (net 143 "3V3_SYS") (pintype "passive"))
  )
	(footprint "data-center-rdimm-ddr4-tester-footprints:R_0402_1005Metric" (layer "F.Cu")
    (at 146.9 127.5 -90)
    (descr "Resistor SMD 0402")
    (tags "resistor SMD 0402")
    (property "Author" "Antmicro")
    (property "License" "Apache-2.0")
    (property "MPN" "CR0402-FX-5111GLF")
    (property "Manufacturer" "Bourns")
    (property "Sheetfile" "interfaces.kicad_sch")
    (property "Sheetname" "Interfaces")
    (property "Tolerance" "1%")
    (property "Val" "5k11")
    (property "ki_description" "5k11 resistor in 0402 package with 1% tolerance")
    (attr smd)
    (fp_text reference "R15" (at -0.78 -0.39 -90) (layer "F.SilkS")
        (effects (font (size 0.7 0.7) (thickness 0.15)) (justify left bottom))
    )
    (fp_text value "R_5k11_0402" (at 0 1.4 -90) (layer "F.Fab") hide
        (effects (font (size 0.7 0.7) (thickness 0.15)) (justify left bottom))
    )
    (fp_text user "${REFERENCE}" (at -0.95 3.168 -90) (layer "F.Fab") hide
        (effects (font (size 0.7 0.7) (thickness 0.15)) (justify left bottom))
    )
    (fp_text user "License: Apache-2.0" (at -0.95 5.169 -90) (layer "F.Fab") hide
        (effects (font (size 0.7 0.7) (thickness 0.15)) (justify left bottom))
    )
    (fp_text user "Author: Antmicro" (at -0.95 4.169 -90) (layer "F.Fab") hide
        (effects (font (size 0.7 0.7) (thickness 0.15)) (justify left bottom))
    )
    (fp_rect (start -0.93 -0.47) (end 0.93 0.47)
      (stroke (width 0.05) (type solid)) (fill none) (layer "F.CrtYd"))
    (fp_rect (start -0.5 -0.25) (end 0.5 0.25)
      (stroke (width 0.15) (type solid)) (fill none) (layer "F.Fab"))
    (pad "1" smd roundrect (at -0.485 0 270) (size 0.59 0.64) (layers "F.Cu" "F.Paste" "F.Mask") (roundrect_rratio 0.25)
      (net 9 "GND") (pintype "passive"))
    (pad "2" smd roundrect (at 0.485 0 270) (size 0.59 0.64) (layers "F.Cu" "F.Paste" "F.Mask") (roundrect_rratio 0.25)
      (net 565 "Net-(J9-CC1)") (pintype "passive"))
  )
)
